# S9S_MB_2U (Grand Teton) — schematic netlist excerpt (pin names and nets, part order shuffled) for the footprints in the layout excerpt that follows; sources: Cadence DE-HDL packaged netlist, KiCad conversion of 03242023_DA0F0TMBIJ0_F0T_Motherboard_J_brd_V01_OCP.brd

PC621  Q_CAPP  560UF 2.5V 20% OSCON  pkg THLF  page 271 : A = PVCCFA_EHV_FIVRA_CPU0 ; B = GND
PC2217  Q_CAP  0.1UF 25V 10% X7R  pkg 0402  page 192 : A = P12V_E1S_0 ; B = GND

U60  NC7SB3157  NC7SB3157P6X IC  pkg SMLF  page 202
  B1  = IRQ_LPC_PIRQA_N_ESPI_ALERT0_R_N
  GND  = GND
  B0  = IRQ_LPC_SERIRQ_ESPI_CS1_R_N
  A  = IRQ_ESPI_LPC_SERIRQ_ALERT_N
  VCC  = PGPPA_AUX
  S  = FM_ESPI_PLD_EN

(kicad_pcb
	(version 20260206)
	(generator "pcbnew")
	(generator_version "10.0")
	(general
		(thickness 1.6)
		(legacy_teardrops no)
	)
	(paper "A4")
	(title_block
		(title "03242023_DA0F0TMBIJ0_F0T_Motherboard_J_brd_V01_OCP.brd")
		(comment 1 "Grand Teton / footprints 2221-2223 of 6105")
	)
	(layers
		(0 "F.Cu" signal "TOP")
		(4 "In1.Cu" signal "GND")
		(6 "In2.Cu" signal "IN1")
		(8 "In3.Cu" signal "GND1")
		(10 "In4.Cu" signal "IN2")
		(12 "In5.Cu" signal "GND2")
		(14 "In6.Cu" signal "IN3")
		(16 "In7.Cu" signal "GND3")
		(18 "In8.Cu" signal "VCC")
		(20 "In9.Cu" signal "VCC1")
		(22 "In10.Cu" signal "GND4")
		(24 "In11.Cu" signal "IN4")
		(26 "In12.Cu" signal "GND5")
		(28 "In13.Cu" signal "IN5")
		(30 "In14.Cu" signal "GND6")
		(32 "In15.Cu" signal "IN6")
		(34 "In16.Cu" signal "GND7")
		(2 "B.Cu" signal "BOTTOM")
		(9 "F.Adhes" user "F.Adhesive")
		(11 "B.Adhes" user "B.Adhesive")
		(13 "F.Paste" user "Package Geometry/Pastemask Top")
		(15 "B.Paste" user "Package Geometry/Pastemask Bottom")
		(5 "F.SilkS" user "Ref Des/Silkscreen Top")
		(7 "B.SilkS" user "Ref Des/Silkscreen Bottom")
		(1 "F.Mask" user "Board Geometry/Soldermask Top")
		(3 "B.Mask" user "Board Geometry/Soldermask Bottom")
		(17 "Dwgs.User" user "User.Drawings")
		(19 "Cmts.User" user "User.Comments")
		(21 "Eco1.User" user "User.Eco1")
		(23 "Eco2.User" user "User.Eco2")
		(25 "Edge.Cuts" user "Board Geometry/Outline")
		(27 "Margin" user)
		(31 "F.CrtYd" user "Package Geometry/Place Bound Top")
		(29 "B.CrtYd" user "Package Geometry/Place Bound Bottom")
		(35 "F.Fab" user "Ref Des/Assembly Top")
		(33 "B.Fab" user "Ref Des/Assembly Bottom")
	)
	(footprint ""
		(layer "F.Cu")
		(at 337.142328 -19.434556 -90)
		(property "Reference" "U60"
			(at 2.376678 -2.681732 0)
			(unlocked yes)
			(layer "F.SilkS")
			(effects
				(font
					(size 0.7874 0.5842)
					(thickness 0.1524)
				)
			)
		)
		(property "Value" ""
			(at 0 0 270)
			(layer "F.Fab")
			(effects
				(font
					(size 1.27 1.27)
				)
			)
		)
		(duplicate_pad_numbers_are_jumpers no)
		(fp_line
			(start -1.7272 1.1176)
			(end -1.7272 -1.1176)
			(stroke
				(width 0.1524)
				(type default)
			)
			(layer "F.SilkS")
		)
		(fp_line
			(start 1.7272 1.1176)
			(end -1.7272 1.1176)
			(stroke
				(width 0.1524)
				(type default)
			)
			(layer "F.SilkS")
		)
		(fp_line
			(start 0 -0.7366)
			(end -0.254 -1.1176)
			(stroke
				(width 0.1524)
				(type default)
			)
			(layer "F.SilkS")
		)
		(fp_line
			(start -0.254 -1.1176)
			(end -1.7272 -1.1176)
			(stroke
				(width 0.1524)
				(type default)
			)
			(layer "F.SilkS")
		)
		(fp_line
			(start 0.254 -1.1176)
			(end 0 -0.7366)
			(stroke
				(width 0.1524)
				(type default)
			)
			(layer "F.SilkS")
		)
		(fp_line
			(start 1.7272 -1.1176)
			(end 1.7272 1.1176)
			(stroke
				(width 0.1524)
				(type default)
			)
			(layer "F.SilkS")
		)
		(fp_line
			(start 1.7272 -1.1176)
			(end 0.254 -1.1176)
			(stroke
				(width 0.1524)
				(type default)
			)
			(layer "F.SilkS")
		)
		(fp_poly
			(pts
				(xy -1.458214 -2.053336) (xy -0.696214 -2.053336) (xy -1.077214 -1.291336)
			)
			(stroke
				(width 0)
				(type default)
			)
			(fill yes)
			(layer "F.SilkS")
		)
		(fp_line
			(start -1.5748 1.1176)
			(end 1.5748 1.1176)
			(stroke
				(width 0.1)
				(type default)
			)
			(layer "F.Fab")
		)
		(fp_line
			(start 1.5748 1.1176)
			(end 1.5748 -1.1176)
			(stroke
				(width 0.1)
				(type default)
			)
			(layer "F.Fab")
		)
		(fp_line
			(start -1.5748 -1.1176)
			(end -1.5748 1.1176)
			(stroke
				(width 0.1)
				(type default)
			)
			(layer "F.Fab")
		)
		(fp_line
			(start 1.5748 -1.1176)
			(end -1.5748 -1.1176)
			(stroke
				(width 0.1)
				(type default)
			)
			(layer "F.Fab")
		)
		(fp_poly
			(pts
				(xy -1.9558 -0.649986) (xy -2.7178 -0.268986) (xy -2.7178 -1.030986)
			)
			(stroke
				(width 0)
				(type default)
			)
			(fill yes)
			(layer "F.Fab")
		)
		(pad "1" smd rect
			(at -0.999998 -0.649986 180)
			(size 0.3556 1.1176)
			(layers "F.Cu" "F.Mask" "F.Paste")
			(net "IRQ_LPC_PIRQA_N_ESPI_ALERT0_R_N")
		)
		(pad "2" smd rect
			(at -0.999998 0 180)
			(size 0.3556 1.1176)
			(layers "F.Cu" "F.Mask" "F.Paste")
			(net "GND")
		)
		(pad "3" smd rect
			(at -0.999998 0.649986 180)
			(size 0.3556 1.1176)
			(layers "F.Cu" "F.Mask" "F.Paste")
			(net "IRQ_LPC_SERIRQ_ESPI_CS1_R_N")
		)
		(pad "4" smd rect
			(at 0.999998 0.649986 180)
			(size 0.3556 1.1176)
			(layers "F.Cu" "F.Mask" "F.Paste")
			(net "IRQ_ESPI_LPC_SERIRQ_ALERT_N")
		)
		(pad "5" smd rect
			(at 0.999998 0 180)
			(size 0.3556 1.1176)
			(layers "F.Cu" "F.Mask" "F.Paste")
			(net "PGPPA_AUX")
		)
		(pad "6" smd rect
			(at 0.999998 -0.649986 180)
			(size 0.3556 1.1176)
			(layers "F.Cu" "F.Mask" "F.Paste")
			(net "FM_ESPI_PLD_EN")
		)
	)
	(footprint ""
		(layer "F.Cu")
		(at 249.713496 -47.078138)
		(property "Reference" "PC2217"
			(at 0 0 0)
			(layer "F.SilkS")
			(hide yes)
			(effects
				(font
					(size 1.27 1.27)
				)
			)
		)
		(property "Value" ""
			(at 0 0 0)
			(layer "F.Fab")
			(effects
				(font
					(size 1.27 1.27)
				)
			)
		)
		(duplicate_pad_numbers_are_jumpers no)
		(fp_line
			(start -0.7874 -0.4064)
			(end 0.7874 -0.4064)
			(stroke
				(width 0.1524)
				(type default)
			)
			(layer "F.SilkS")
		)
		(fp_line
			(start -0.7874 0.4064)
			(end -0.7874 -0.4064)
			(stroke
				(width 0.1524)
				(type default)
			)
			(layer "F.SilkS")
		)
		(fp_line
			(start 0.7874 -0.4064)
			(end 0.7874 0.4064)
			(stroke
				(width 0.1524)
				(type default)
			)
			(layer "F.SilkS")
		)
		(fp_line
			(start 0.7874 0.4064)
			(end -0.7874 0.4064)
			(stroke
				(width 0.1524)
				(type default)
			)
			(layer "F.SilkS")
		)
		(fp_line
			(start -0.67945 -0.305054)
			(end -0.12065 -0.305054)
			(stroke
				(width 0.1)
				(type default)
			)
			(layer "F.Fab")
		)
		(fp_line
			(start -0.67945 0.3048)
			(end -0.67945 -0.305054)
			(stroke
				(width 0.1)
				(type default)
			)
			(layer "F.Fab")
		)
		(fp_line
			(start -0.12065 -0.305054)
			(end -0.12065 -0.2794)
			(stroke
				(width 0.1)
				(type default)
			)
			(layer "F.Fab")
		)
		(fp_line
			(start -0.12065 -0.2794)
			(end 0.12065 -0.2794)
			(stroke
				(width 0.1)
				(type default)
			)
			(layer "F.Fab")
		)
		(fp_line
			(start -0.12065 0.2794)
			(end -0.12065 0.3048)
			(stroke
				(width 0.1)
				(type default)
			)
			(layer "F.Fab")
		)
		(fp_line
			(start -0.12065 0.3048)
			(end -0.67945 0.3048)
			(stroke
				(width 0.1)
				(type default)
			)
			(layer "F.Fab")
		)
		(fp_line
			(start 0.120396 0.2794)
			(end -0.12065 0.2794)
			(stroke
				(width 0.1)
				(type default)
			)
			(layer "F.Fab")
		)
		(fp_line
			(start 0.120396 0.3048)
			(end 0.120396 0.2794)
			(stroke
				(width 0.1)
				(type default)
			)
			(layer "F.Fab")
		)
		(fp_line
			(start 0.12065 -0.3048)
			(end 0.67945 -0.3048)
			(stroke
				(width 0.1)
				(type default)
			)
			(layer "F.Fab")
		)
		(fp_line
			(start 0.12065 -0.2794)
			(end 0.12065 -0.3048)
			(stroke
				(width 0.1)
				(type default)
			)
			(layer "F.Fab")
		)
		(fp_line
			(start 0.67945 -0.3048)
			(end 0.67945 0.3048)
			(stroke
				(width 0.1)
				(type default)
			)
			(layer "F.Fab")
		)
		(fp_line
			(start 0.67945 0.3048)
			(end 0.120396 0.3048)
			(stroke
				(width 0.1)
				(type default)
			)
			(layer "F.Fab")
		)
		(pad "1" smd circle
			(at -0.40005 0)
			(size 0 0)
			(layers "F.Cu" "F.Mask" "F.Paste")
			(net "P12V_E1S_0")
		)
		(pad "2" smd circle
			(at 0.40005 0)
			(size 0 0)
			(layers "F.Cu" "F.Mask" "F.Paste")
			(net "GND")
		)
	)
	(footprint ""
		(layer "F.Cu")
		(at 287.2994 -346.700348)
		(property "Reference" "PC621"
			(at 0 0 0)
			(layer "F.SilkS")
			(hide yes)
			(effects
				(font
					(size 1.27 1.27)
				)
			)
		)
		(property "Value" ""
			(at 0 0 0)
			(layer "F.Fab")
			(effects
				(font
					(size 1.27 1.27)
				)
			)
		)
		(duplicate_pad_numbers_are_jumpers no)
		(fp_line
			(start 2.750058 0.999998)
			(end -2.750058 0.999998)
			(stroke
				(width 0.1524)
				(type default)
			)
			(layer "F.SilkS")
		)
		(fp_circle
			(center 0 0.999998)
			(end 2.750058 0.999998)
			(stroke
				(width 0.1524)
				(type default)
			)
			(fill no)
			(layer "F.SilkS")
		)
		(fp_poly
			(pts
				(arc
					(start 2.750058 0.999998)
					(mid 0 3.750056)
					(end -2.750058 0.999998)
				)
			)
			(stroke
				(width 0)
				(type default)
			)
			(fill yes)
			(layer "F.SilkS")
		)
		(fp_circle
			(center 0 0.999998)
			(end 2.750058 0.999998)
			(stroke
				(width 0.1)
				(type default)
			)
			(fill no)
			(layer "F.Fab")
		)
		(pad "1" thru_hole rect
			(at 0 0)
			(size 1.5748 1.5748)
			(drill 1.0668)
			(layers "*.Cu" "*.Mask")
			(remove_unused_layers no)
			(net "PVCCFA_EHV_FIVRA_CPU0")
			(clearance 0)
			(padstack
				(mode front_inner_back)
				(layer "Inner"
					(shape circle)
					(size 1.5748 1.5748)
					(clearance 0)
				)
				(layer "B.Cu"
					(shape rect)
					(size 1.5748 1.5748)
					(clearance 0)
				)
			)
		)
		(pad "2" thru_hole circle
			(at 0 1.999996)
			(size 1.5748 1.5748)
			(drill 1.0668)
			(layers "*.Cu" "*.Mask")
			(remove_unused_layers no)
			(net "GND")
			(clearance 0)
		)
	)
)
